# TIMECARD (Time Appliance Project (Time Card)) — schematic netlist excerpt (pin names and nets, part order shuffled) for the footprints in the layout excerpt that follows; sources: Cadence DE-HDL packaged netlist, KiCad conversion of R4006-B0001-02_R01.brd

TP27  TP_PIONT  pkg TP010CT020B030_PTH  page 25 : \1\ = R_SHT3X_ALERT_N
C287  CAPACITOR  10UF 6.3V 20%  pkg SMC_0402R_H022  page 9 : \1\ = XP3R3V_AUX_PCIE ; \2\ = SG

(kicad_pcb
	(version 20260206)
	(generator "pcbnew")
	(generator_version "10.0")
	(general
		(thickness 1.6)
		(legacy_teardrops no)
	)
	(paper "A4")
	(title_block
		(title "timecard-production-celestica-r4006 — R4006-B0001-02_R01.brd")
		(comment 1 "Time Appliance Project (Time Card) / footprints 649-650 of 1113")
	)
	(layers
		(0 "F.Cu" signal "TOP")
		(4 "In1.Cu" signal "L02_GND1")
		(6 "In2.Cu" signal "L03_SIG1")
		(8 "In3.Cu" signal "L04_GND2")
		(10 "In4.Cu" signal "L05_VCC1")
		(12 "In5.Cu" signal "L06_VCC2")
		(14 "In6.Cu" signal "L07_GND3")
		(16 "In7.Cu" signal "L08_SIG2")
		(18 "In8.Cu" signal "L09_GND4")
		(2 "B.Cu" signal "BOTTOM")
		(9 "F.Adhes" user "F.Adhesive")
		(11 "B.Adhes" user "B.Adhesive")
		(13 "F.Paste" user "Package Geometry/Pastemask Top")
		(15 "B.Paste" user "Package Geometry/Pastemask Bottom")
		(5 "F.SilkS" user "Ref Des/Silkscreen Top")
		(7 "B.SilkS" user "Ref Des/Silkscreen Bottom")
		(1 "F.Mask" user "Board Geometry/Soldermask Top")
		(3 "B.Mask" user "Board Geometry/Soldermask Bottom")
		(17 "Dwgs.User" user "User.Drawings")
		(19 "Cmts.User" user "User.Comments")
		(21 "Eco1.User" user "User.Eco1")
		(23 "Eco2.User" user "User.Eco2")
		(25 "Edge.Cuts" user "Board Geometry/Outline")
		(27 "Margin" user)
		(31 "F.CrtYd" user "Package Geometry/Place Bound Top")
		(29 "B.CrtYd" user "Package Geometry/Place Bound Bottom")
		(35 "F.Fab" user "Ref Des/Assembly Top")
		(33 "B.Fab" user "Ref Des/Assembly Bottom")
	)
	(footprint ""
		(layer "F.Cu")
		(at 53.467 -15.621 90)
		(property "Reference" "C287"
			(at 3.556 0.42037 90)
			(unlocked yes)
			(layer "F.SilkS")
			(effects
				(font
					(size 0.7874 0.5842)
					(thickness 0.1524)
				)
			)
		)
		(property "Value" "VAL*"
			(at 0.0762 2.067306 90)
			(unlocked yes)
			(layer "F.Fab")
			(hide yes)
			(effects
				(font
					(size 0.7874 0.5842)
					(thickness 0.1524)
				)
			)
		)
		(property "Device Type" "CAPACITOR-G105-0C106-BM,10UF,2A"
			(at 0.0508 1.127506 90)
			(unlocked yes)
			(layer "F.Fab")
			(hide yes)
			(effects
				(font
					(size 0.7874 0.5842)
					(thickness 0.1524)
				)
			)
		)
		(property "User Part Number" "PARTNUM*"
			(at 0.1016 4.023106 90)
			(unlocked yes)
			(layer "Cmts.User")
			(hide yes)
			(effects
				(font
					(size 0.7874 0.5842)
					(thickness 0.1524)
				)
			)
		)
		(property "Tolerance" "TOL*"
			(at 0.0762 3.032506 90)
			(unlocked yes)
			(layer "Cmts.User")
			(hide yes)
			(effects
				(font
					(size 0.7874 0.5842)
					(thickness 0.1524)
				)
			)
		)
		(duplicate_pad_numbers_are_jumpers no)
		(fp_line
			(start 1.143 -0.5588)
			(end -1.143 -0.5588)
			(stroke
				(width 0.1)
				(type default)
			)
			(layer "F.SilkS")
		)
		(fp_line
			(start -1.143 -0.5588)
			(end -1.143 0.5588)
			(stroke
				(width 0.1)
				(type default)
			)
			(layer "F.SilkS")
		)
		(fp_line
			(start 1.143 0.5588)
			(end 1.143 -0.5588)
			(stroke
				(width 0.1)
				(type default)
			)
			(layer "F.SilkS")
		)
		(fp_line
			(start -1.143 0.5588)
			(end 1.143 0.5588)
			(stroke
				(width 0.1)
				(type default)
			)
			(layer "F.SilkS")
		)
		(fp_poly
			(pts
				(xy -1.143 0.5588) (xy 1.143 0.5588) (xy 1.143 -0.5588) (xy -1.143 -0.5588)
			)
			(stroke
				(width 0)
				(type default)
			)
			(fill no)
			(layer "F.CrtYd")
		)
		(fp_line
			(start 0.508 -0.3048)
			(end -0.508 -0.3048)
			(stroke
				(width 0.1)
				(type default)
			)
			(layer "F.Fab")
		)
		(fp_line
			(start -0.508 -0.3048)
			(end -0.508 0.3048)
			(stroke
				(width 0.1)
				(type default)
			)
			(layer "F.Fab")
		)
		(fp_line
			(start 0.508 0.3048)
			(end 0.508 -0.3048)
			(stroke
				(width 0.1)
				(type default)
			)
			(layer "F.Fab")
		)
		(fp_line
			(start -0.508 0.3048)
			(end 0.508 0.3048)
			(stroke
				(width 0.1)
				(type default)
			)
			(layer "F.Fab")
		)
		(pad "1" smd rect
			(at -0.5334 0 90)
			(size 0.7112 0.6096)
			(layers "F.Cu" "F.Mask" "F.Paste")
			(net "XP3R3V_AUX_PCIE")
		)
		(pad "2" smd rect
			(at 0.5334 0 90)
			(size 0.7112 0.6096)
			(layers "F.Cu" "F.Mask" "F.Paste")
			(net "SG")
		)
		(zone
			(layer "F.Cu")
			(hatch none 0.5)
			(connect_pads
				(clearance 0)
			)
			(min_thickness 0.25)
			(keepout
				(tracks not_allowed)
				(vias allowed)
				(pads allowed)
				(copperpour not_allowed)
				(footprints allowed)
			)
			(placement
				(enabled no)
				(sheetname "")
			)
			(fill
				(thermal_gap 0.5)
				(thermal_bridge_width 0.5)
				(island_removal_mode 0)
			)
			(polygon
				(pts
					(xy 53.7718 -15.5448) (xy 53.7718 -15.6972) (xy 53.1622 -15.6972) (xy 53.1622 -15.5448)
				)
			)
		)
		(zone
			(layer "F.Cu")
			(hatch none 0.5)
			(connect_pads
				(clearance 0)
			)
			(min_thickness 0.25)
			(keepout
				(tracks allowed)
				(vias not_allowed)
				(pads allowed)
				(copperpour not_allowed)
				(footprints allowed)
			)
			(placement
				(enabled no)
				(sheetname "")
			)
			(fill
				(thermal_gap 0.5)
				(thermal_bridge_width 0.5)
				(island_removal_mode 0)
			)
			(polygon
				(pts
					(xy 53.7718 -15.5448) (xy 53.7718 -15.6972) (xy 53.1622 -15.6972) (xy 53.1622 -15.5448)
				)
			)
		)
	)
	(footprint ""
		(layer "F.Cu")
		(at 149.098 -46.736)
		(property "Reference" "TP27"
			(at -2.4892 1.43637 0)
			(unlocked yes)
			(layer "F.SilkS")
			(effects
				(font
					(size 0.7874 0.5842)
					(thickness 0.1524)
				)
				(justify left)
			)
		)
		(property "Value" ""
			(at 0 0 0)
			(layer "F.Fab")
			(effects
				(font
					(size 1.27 1.27)
				)
			)
		)
		(property "Device Type" "TP_PIONT-TP010CT020B030_PTH-TPA"
			(at -1.341882 0.996696 0)
			(unlocked yes)
			(layer "F.Fab")
			(hide yes)
			(effects
				(font
					(size 0.7874 0.5842)
					(thickness 0.000001)
				)
				(justify left)
			)
		)
		(duplicate_pad_numbers_are_jumpers no)
		(fp_poly
			(pts
				(arc
					(start 0.889 0)
					(mid -0.889 0)
					(end 0.889 0)
				)
			)
			(stroke
				(width 0)
				(type default)
			)
			(fill no)
			(layer "B.CrtYd")
		)
		(fp_poly
			(pts
				(arc
					(start 0.889 0)
					(mid -0.889 0)
					(end 0.889 0)
				)
			)
			(stroke
				(width 0)
				(type default)
			)
			(fill no)
			(layer "F.CrtYd")
		)
		(pad "1" thru_hole circle
			(at 0 0)
			(size 0.508 0.508)
			(drill 0.254)
			(layers "*.Cu" "*.Mask")
			(remove_unused_layers no)
			(net "R_SHT3X_ALERT_N")
			(clearance 0.1016)
			(padstack
				(mode front_inner_back)
				(layer "Inner"
					(shape circle)
					(size 0.508 0.508)
					(clearance 0.1016)
				)
				(layer "B.Cu"
					(shape circle)
					(size 0.762 0.762)
					(clearance -0.0254)
				)
			)
		)
	)
)
